(kicad_pcb
	(version 20260206)
	(generator "pcbnew")
	(generator_version "10.0")
	(general
		(thickness 1.21888)
		(legacy_teardrops no)
	)
	(paper "A4")
	(title_block
		(title "timecard-v9 — TimeCard-DC-V9_EXP.PcbDoc")
		(comment 1 "Time Appliance Project (Time Card) / footprints 228-234 of 402")
	)
	(layers
		(0 "F.Cu" signal "TOP")
		(4 "In1.Cu" signal "SGND")
		(6 "In2.Cu" signal "IN1")
		(8 "In3.Cu" signal "IN2")
		(10 "In4.Cu" signal "SGND1")
		(2 "B.Cu" signal "BOTTOM")
		(9 "F.Adhes" user "F.Adhesive")
		(11 "B.Adhes" user "B.Adhesive")
		(13 "F.Paste" user "Top Paste")
		(15 "B.Paste" user "Bottom Paste")
		(5 "F.SilkS" user "Top Overlay")
		(7 "B.SilkS" user "Bottom Overlay")
		(1 "F.Mask" user "Top Solder")
		(3 "B.Mask" user "Bottom Solder")
		(17 "Dwgs.User" user "User.Drawings")
		(19 "Cmts.User" user "User.Comments")
		(21 "Eco1.User" user "User.Eco1")
		(23 "Eco2.User" user "User.Eco2")
		(25 "Edge.Cuts" user)
		(27 "Margin" user)
		(31 "F.CrtYd" user "Top Courtyard")
		(29 "B.CrtYd" user "Bottom Courtyard")
		(35 "F.Fab" user "Top Component Center")
		(33 "B.Fab" user "Bottom Component Center")
	)
	(footprint "Vault:FP-ERJ2RK-IPC_A"
		(layer "F.Cu")
		(at 191.4216 74.5162 180)
		(property "Reference" "R77"
			(at -0.3286 1.573079 0)
			(unlocked yes)
			(layer "F.SilkS")
			(effects
				(font
					(size 0.762 0.762)
					(thickness 0.2286)
				)
			)
		)
		(property "Value" "200_1%_0402"
			(at -2.935471 7.782475 90)
			(unlocked yes)
			(layer "F.SilkS")
			(hide yes)
			(effects
				(font
					(size 0.762 0.762)
					(thickness 0.2286)
				)
			)
		)
		(sheetname "03-POWER")
		(sheetfile "03-POWER.kicad_sch")
		(duplicate_pad_numbers_are_jumpers no)
		(fp_line
			(start 0.83624 0.73624)
			(end -0.83624 0.73624)
			(stroke
				(width 0.2)
				(type solid)
			)
			(layer "F.SilkS")
		)
		(fp_line
			(start 0.83624 -0.73624)
			(end -0.83624 -0.73624)
			(stroke
				(width 0.2)
				(type solid)
			)
			(layer "F.SilkS")
		)
		(fp_line
			(start 1.03624 0.53624)
			(end -1.03624 0.53624)
			(stroke
				(width 0.2)
				(type solid)
			)
			(layer "F.CrtYd")
		)
		(fp_line
			(start 1.03624 -0.53624)
			(end 1.03624 0.53624)
			(stroke
				(width 0.2)
				(type solid)
			)
			(layer "F.CrtYd")
		)
		(fp_line
			(start 1.03624 -0.53624)
			(end -1.03624 -0.53624)
			(stroke
				(width 0.2)
				(type solid)
			)
			(layer "F.CrtYd")
		)
		(fp_line
			(start -1.03624 -0.53624)
			(end -1.03624 0.53624)
			(stroke
				(width 0.2)
				(type solid)
			)
			(layer "F.CrtYd")
		)
		(fp_line
			(start 1.03624 0.53624)
			(end -1.03624 0.53624)
			(stroke
				(width 0.2)
				(type solid)
			)
			(layer "F.Fab")
		)
		(fp_line
			(start 1.03624 -0.53624)
			(end 1.03624 0.53624)
			(stroke
				(width 0.2)
				(type solid)
			)
			(layer "F.Fab")
		)
		(fp_line
			(start 1.03624 -0.53624)
			(end -1.03624 -0.53624)
			(stroke
				(width 0.2)
				(type solid)
			)
			(layer "F.Fab")
		)
		(fp_line
			(start 0.5 0)
			(end -0.5 0)
			(stroke
				(width 0.1)
				(type solid)
			)
			(layer "F.Fab")
		)
		(fp_line
			(start 0 -0.5)
			(end 0 0.5)
			(stroke
				(width 0.1)
				(type solid)
			)
			(layer "F.Fab")
		)
		(fp_line
			(start -1.03624 -0.53624)
			(end -1.03624 0.53624)
			(stroke
				(width 0.2)
				(type solid)
			)
			(layer "F.Fab")
		)
		(fp_text user "${REFERENCE}"
			(at -0.00001 0.10711 180)
			(unlocked yes)
			(layer "F.Fab")
			(effects
				(font
					(face "Arial")
					(size 0.63 0.63)
					(thickness 0.1)
				)
				(justify left bottom)
			)
		)
		(pad "1" smd rect
			(at -0.50215 0 180)
			(size 0.66818 0.67248)
			(layers "F.Cu" "F.Mask" "F.Paste")
			(net "GND")
			(solder_mask_margin 0)
			(solder_paste_margin 0)
		)
		(pad "2" smd rect
			(at 0.50215 0 180)
			(size 0.66818 0.67248)
			(layers "F.Cu" "F.Mask" "F.Paste")
			(net "NetD20_1")
			(solder_mask_margin 0)
			(solder_paste_margin 0)
		)
	)
	(footprint "Vault:FP-RUT0012A-MFG"
		(layer "F.Cu")
		(at 143.7216 104.7162 90)
		(property "Reference" "U23"
			(at 2.273079 -2.6714 0)
			(unlocked yes)
			(layer "F.SilkS")
			(effects
				(font
					(size 0.762 0.762)
					(thickness 0.2286)
				)
			)
		)
		(property "Value" "TMUX1072RUTR"
			(at 7.426675 3.164071 90)
			(unlocked yes)
			(layer "F.SilkS")
			(hide yes)
			(effects
				(font
					(size 0.762 0.762)
					(thickness 0.2286)
				)
			)
		)
		(sheetname "09-USBUart_PPSMUX_UARTMUX")
		(sheetfile "09-USBUart_PPSMUX_UARTMUX.kicad_sch")
		(duplicate_pad_numbers_are_jumpers no)
		(fp_line
			(start -0.9 -1.525)
			(end 0.9 -1.525)
			(stroke
				(width 0.2)
				(type solid)
			)
			(layer "F.SilkS")
		)
		(fp_line
			(start -0.9 1.525)
			(end 0.9 1.525)
			(stroke
				(width 0.2)
				(type solid)
			)
			(layer "F.SilkS")
		)
		(fp_circle
			(center -1.575 -0.8)
			(end -1.45 -0.8)
			(stroke
				(width 0.25)
				(type solid)
			)
			(fill no)
			(layer "F.SilkS")
		)
		(fp_rect
			(start 0.35004 -0.69996)
			(end 0.85004 -0.89996)
			(stroke
				(width 0)
				(type default)
			)
			(fill yes)
			(layer "F.Paste")
		)
		(fp_rect
			(start -0.10006 -0.49994)
			(end 0.09994 -0.99994)
			(stroke
				(width 0)
				(type default)
			)
			(fill yes)
			(layer "F.Paste")
		)
		(fp_rect
			(start 0.34996 -0.30004)
			(end 0.84996 -0.50004)
			(stroke
				(width 0)
				(type default)
			)
			(fill yes)
			(layer "F.Paste")
		)
		(fp_rect
			(start -0.84996 -0.29996)
			(end -0.34996 -0.49996)
			(stroke
				(width 0)
				(type default)
			)
			(fill yes)
			(layer "F.Paste")
		)
		(fp_rect
			(start 0.34996 0.09996)
			(end 0.84996 -0.10004)
			(stroke
				(width 0)
				(type default)
			)
			(fill yes)
			(layer "F.Paste")
		)
		(fp_rect
			(start -0.84996 0.10004)
			(end -0.34996 -0.09996)
			(stroke
				(width 0)
				(type default)
			)
			(fill yes)
			(layer "F.Paste")
		)
		(fp_rect
			(start 0.34996 0.49996)
			(end 0.84996 0.29996)
			(stroke
				(width 0)
				(type default)
			)
			(fill yes)
			(layer "F.Paste")
		)
		(fp_rect
			(start -0.84996 0.50004)
			(end -0.34996 0.30004)
			(stroke
				(width 0)
				(type default)
			)
			(fill yes)
			(layer "F.Paste")
		)
		(fp_rect
			(start -0.850045 0.899965)
			(end -0.350035 0.699965)
			(stroke
				(width 0)
				(type default)
			)
			(fill yes)
			(layer "F.Paste")
		)
		(fp_rect
			(start 0.35004 0.90004)
			(end 0.85004 0.70004)
			(stroke
				(width 0)
				(type default)
			)
			(fill yes)
			(layer "F.Paste")
		)
		(fp_rect
			(start -0.09994 0.99994)
			(end 0.10006 0.49994)
			(stroke
				(width 0)
				(type default)
			)
			(fill yes)
			(layer "F.Paste")
		)
		(fp_poly
			(pts
				(xy -0.5 -1) (xy -0.35 -1) (xy -0.35 -0.7) (xy -0.85 -0.7) (xy -0.85 -0.9) (xy -0.5 -0.9)
			)
			(stroke
				(width 0)
				(type default)
			)
			(fill yes)
			(layer "F.Paste")
		)
		(fp_line
			(start 1.05 -1.2)
			(end 1.05 1.2)
			(stroke
				(width 0.2)
				(type solid)
			)
			(layer "F.CrtYd")
		)
		(fp_line
			(start -1.05 -1.2)
			(end 1.05 -1.2)
			(stroke
				(width 0.2)
				(type solid)
			)
			(layer "F.CrtYd")
		)
		(fp_line
			(start -1.05 -1.2)
			(end -1.05 1.2)
			(stroke
				(width 0.2)
				(type solid)
			)
			(layer "F.CrtYd")
		)
		(fp_line
			(start -1.05 1.2)
			(end 1.05 1.2)
			(stroke
				(width 0.2)
				(type solid)
			)
			(layer "F.CrtYd")
		)
		(fp_line
			(start 1.05 -1.2)
			(end 1.05 1.2)
			(stroke
				(width 0.2)
				(type solid)
			)
			(layer "F.Fab")
		)
		(fp_line
			(start -1.05 -1.2)
			(end 1.05 -1.2)
			(stroke
				(width 0.2)
				(type solid)
			)
			(layer "F.Fab")
		)
		(fp_line
			(start -1.05 -1.2)
			(end -1.05 1.2)
			(stroke
				(width 0.2)
				(type solid)
			)
			(layer "F.Fab")
		)
		(fp_line
			(start 0 -0.5)
			(end 0 0.5)
			(stroke
				(width 0.1)
				(type solid)
			)
			(layer "F.Fab")
		)
		(fp_line
			(start -0.5 0)
			(end 0.5 0)
			(stroke
				(width 0.1)
				(type solid)
			)
			(layer "F.Fab")
		)
		(fp_line
			(start -1.05 1.2)
			(end 1.05 1.2)
			(stroke
				(width 0.2)
				(type solid)
			)
			(layer "F.Fab")
		)
		(fp_text user "${REFERENCE}"
			(at -0.00001 0.09602 90)
			(unlocked yes)
			(layer "F.Fab")
			(effects
				(font
					(face "Arial")
					(size 0.63 0.63)
					(thickness 0.1)
				)
				(justify left bottom)
			)
		)
		(pad "" smd custom
			(at -0.5 -1.1)
			(size 0.000001 0.000001)
			(layers "F.Cu" "F.Mask")
			(solder_mask_margin 0)
			(thermal_bridge_angle 90)
			(options
				(clearance outline)
				(anchor circle)
			)
			(primitives
				(gr_poly
					(pts
						(xy 0 0) (xy 0 -0.15) (xy 0.4 -0.15) (xy 0.4 0.45) (xy 0.2 0.45) (xy 0.2 0)
					)
					(width 0)
					(fill yes)
				)
			)
		)
		(pad "1" smd circle
			(at -0.45 -0.8 90)
			(size 0.18 0.18)
			(layers "F.Cu" "F.Mask" "F.Paste")
			(net "DIP_SW_PPS_SEL")
			(solder_mask_margin 0)
			(solder_paste_margin -1000)
			(thermal_bridge_angle 90)
		)
		(pad "2" smd rect
			(at -0.65 -0.4 90)
			(size 0.6 0.2)
			(layers "F.Cu" "F.Mask" "F.Paste")
			(net "NetR97_2")
			(solder_mask_margin 0)
			(solder_paste_margin -1000)
		)
		(pad "3" smd rect
			(at -0.65 0 90)
			(size 0.6 0.2)
			(layers "F.Cu" "F.Mask" "F.Paste")
			(net "GND")
			(solder_mask_margin 0)
			(solder_paste_margin -1000)
		)
		(pad "4" smd rect
			(at -0.65 0.4 90)
			(size 0.6 0.2)
			(layers "F.Cu" "F.Mask" "F.Paste")
			(net "NetR99_2")
			(solder_mask_margin 0)
			(solder_paste_margin -1000)
		)
		(pad "5" smd rect
			(at -0.65 0.8 90)
			(size 0.6 0.2)
			(layers "F.Cu" "F.Mask" "F.Paste")
			(net "DIP_SW_PPS_SEL")
			(solder_mask_margin 0)
			(solder_paste_margin -1000)
		)
		(pad "6" smd rect
			(at 0 0.8 90)
			(size 0.2 0.6)
			(layers "F.Cu" "F.Mask" "F.Paste")
			(net "GND")
			(solder_mask_margin 0)
			(solder_paste_margin -1000)
		)
		(pad "7" smd rect
			(at 0.65 0.8 90)
			(size 0.6 0.2)
			(layers "F.Cu" "F.Mask" "F.Paste")
			(net "FPGA_MAC_PPS_IN0-")
			(solder_mask_margin 0)
			(solder_paste_margin -1000)
		)
		(pad "8" smd rect
			(at 0.65 0.4 90)
			(size 0.6 0.2)
			(layers "F.Cu" "F.Mask" "F.Paste")
			(net "NetR98_2")
			(solder_mask_margin 0)
			(solder_paste_margin -1000)
		)
		(pad "9" smd rect
			(at 0.65 0 90)
			(size 0.6 0.2)
			(layers "F.Cu" "F.Mask" "F.Paste")
			(net "+3.3V")
			(solder_mask_margin 0)
			(solder_paste_margin -1000)
		)
		(pad "10" smd rect
			(at 0.65 -0.4 90)
			(size 0.6 0.2)
			(layers "F.Cu" "F.Mask" "F.Paste")
			(net "NetR96_2")
			(solder_mask_margin 0)
			(solder_paste_margin -1000)
		)
		(pad "11" smd rect
			(at 0.65 -0.8 90)
			(size 0.6 0.2)
			(layers "F.Cu" "F.Mask" "F.Paste")
			(net "FPGA_MAC_PPS_OUT-")
			(solder_mask_margin 0)
			(solder_paste_margin -1000)
		)
		(pad "12" smd rect
			(at 0 -0.8 90)
			(size 0.2 0.6)
			(layers "F.Cu" "F.Mask" "F.Paste")
			(net "GND")
			(solder_mask_margin 0)
			(solder_paste_margin -1000)
		)
	)
	(footprint "Vault:TECO-1909763-1_V"
		(layer "F.Cu")
		(at 77.19563 95.0786 -90)
		(property "Reference" "J1"
			(at -3.435469 -0.054565 0)
			(unlocked yes)
			(layer "F.SilkS")
			(effects
				(font
					(size 0.762 0.762)
					(thickness 0.2286)
				)
			)
		)
		(property "Value" "1909763-1"
			(at 4.582685 3.722871 270)
			(unlocked yes)
			(layer "F.SilkS")
			(hide yes)
			(effects
				(font
					(size 0.762 0.762)
					(thickness 0.2286)
				)
			)
		)
		(sheetname "01-USER_IO")
		(sheetfile "01-USER_IO.kicad_sch")
		(duplicate_pad_numbers_are_jumpers no)
		(fp_line
			(start 0.55 -1.3)
			(end -0.55 -1.3)
			(stroke
				(width 0.2)
				(type solid)
			)
			(layer "F.SilkS")
		)
		(fp_circle
			(center -1.778 1.65)
			(end -1.903 1.65)
			(stroke
				(width 0.25)
				(type solid)
			)
			(fill no)
			(layer "F.SilkS")
		)
		(pad "1" smd rect
			(at -1.475 0 270)
			(size 1.05 2.2)
			(layers "F.Cu" "F.Mask" "F.Paste")
			(net "GND")
		)
		(pad "2" smd rect
			(at 0 1.525 270)
			(size 1 1.05)
			(layers "F.Cu" "F.Mask" "F.Paste")
			(net "NetAN1_1")
		)
		(pad "3" smd rect
			(at 1.475 0 270)
			(size 1.05 2.2)
			(layers "F.Cu" "F.Mask" "F.Paste")
			(net "GND")
		)
	)
	(footprint "Vault:RESC1005X40X25LL05T05"
		(layer "F.Cu")
		(at 118.58072 83.9662)
		(property "Reference" "R71"
			(at -0.030515 -0.923069 0)
			(unlocked yes)
			(layer "F.SilkS")
			(effects
				(font
					(size 0.762 0.762)
					(thickness 0.2286)
				)
			)
		)
		(property "Value" "DNI_0_1%_0402"
			(at -2.884671 8.54431 270)
			(unlocked yes)
			(layer "F.SilkS")
			(hide yes)
			(effects
				(font
					(size 0.762 0.762)
					(thickness 0.2286)
				)
			)
		)
		(sheetname "05-GPS_IMU_SENSORS")
		(sheetfile "05-GPS_IMU_SENSORS.kicad_sch")
		(duplicate_pad_numbers_are_jumpers no)
		(pad "1" smd rect
			(at -0.4 0 90)
			(size 0.45 0.45)
			(layers "F.Cu" "F.Mask" "F.Paste")
			(net "BNO_XIN32")
		)
		(pad "2" smd rect
			(at 0.40001 0 90)
			(size 0.45 0.45)
			(layers "F.Cu" "F.Mask" "F.Paste")
			(net "FPGA_BNO_XIN32")
		)
	)
	(footprint "Vault:SMTC-TSM-105-01-X-DV"
		(layer "F.Cu")
		(at 227.6466 139.7762 90)
		(property "Reference" "P4"
			(at 6.633079 -3.321795 0)
			(unlocked yes)
			(layer "F.SilkS")
			(effects
				(font
					(size 0.762 0.762)
					(thickness 0.2032)
				)
			)
		)
		(property "Value" "TSM-105-01-L-DV"
			(at -8.777471 6.917965 0)
			(unlocked yes)
			(layer "F.SilkS")
			(hide yes)
			(effects
				(font
					(size 0.762 0.762)
					(thickness 0.2032)
				)
			)
		)
		(sheetname "04-PCIe_JTAG")
		(sheetfile "04-PCIe_JTAG.kicad_sch")
		(duplicate_pad_numbers_are_jumpers no)
		(fp_line
			(start 6.35 -2.54)
			(end 6.35 2.54)
			(stroke
				(width 0.2)
				(type solid)
			)
			(layer "F.SilkS")
		)
		(fp_line
			(start 6.115 -2.54)
			(end 6.35 -2.54)
			(stroke
				(width 0.2)
				(type solid)
			)
			(layer "F.SilkS")
		)
		(fp_line
			(start -6.35 -2.54)
			(end -6.115 -2.54)
			(stroke
				(width 0.2)
				(type solid)
			)
			(layer "F.SilkS")
		)
		(fp_line
			(start -6.35 -2.54)
			(end -6.35 2.54)
			(stroke
				(width 0.2)
				(type solid)
			)
			(layer "F.SilkS")
		)
		(fp_line
			(start 6.115 2.54)
			(end 6.35 2.54)
			(stroke
				(width 0.2)
				(type solid)
			)
			(layer "F.SilkS")
		)
		(fp_line
			(start -6.35 2.54)
			(end -6.115 2.54)
			(stroke
				(width 0.2)
				(type solid)
			)
			(layer "F.SilkS")
		)
		(fp_circle
			(center -6.985 2.54)
			(end -6.86 2.54)
			(stroke
				(width 0.25)
				(type solid)
			)
			(fill no)
			(layer "F.SilkS")
		)
		(pad "1" smd rect
			(at -5.08 2.475 90)
			(size 1.27 3.68)
			(layers "F.Cu" "F.Mask" "F.Paste")
			(net "NetP4_1")
		)
		(pad "2" smd rect
			(at -5.08 -2.475 90)
			(size 1.27 3.68)
			(layers "F.Cu" "F.Mask" "F.Paste")
			(net "GND")
		)
		(pad "3" smd rect
			(at -2.54 2.475 90)
			(size 1.27 3.68)
			(layers "F.Cu" "F.Mask" "F.Paste")
			(net "NetP4_3")
		)
		(pad "4" smd rect
			(at -2.54 -2.475 90)
			(size 1.27 3.68)
			(layers "F.Cu" "F.Mask" "F.Paste")
			(net "+3.3V")
		)
		(pad "5" smd rect
			(at 0 2.475 90)
			(size 1.27 3.68)
			(layers "F.Cu" "F.Mask" "F.Paste")
			(net "NetP4_5")
		)
		(pad "6" smd rect
			(at 0 -2.475 90)
			(size 1.27 3.68)
			(layers "F.Cu" "F.Mask" "F.Paste")
			(net "+3.3V")
		)
		(pad "7" smd rect
			(at 2.54 2.475 90)
			(size 1.27 3.68)
			(layers "F.Cu" "F.Mask" "F.Paste")
		)
		(pad "8" smd rect
			(at 2.54 -2.475 90)
			(size 1.27 3.68)
			(layers "F.Cu" "F.Mask" "F.Paste")
		)
		(pad "9" smd rect
			(at 5.08 2.475 90)
			(size 1.27 3.68)
			(layers "F.Cu" "F.Mask" "F.Paste")
			(net "NetP4_9")
		)
		(pad "10" smd rect
			(at 5.08 -2.475 90)
			(size 1.27 3.68)
			(layers "F.Cu" "F.Mask" "F.Paste")
			(net "GND")
		)
	)
	(footprint "Vault:RESC1005X40X25NL05T05"
		(layer "F.Cu")
		(at 189.3216 133.9162 -90)
		(property "Reference" "R156"
			(at 2.65329 0.357071 270)
			(unlocked yes)
			(layer "F.SilkS")
			(effects
				(font
					(size 0.762 0.762)
					(thickness 0.2032)
				)
			)
		)
		(property "Value" "DNI_27_1%_0402"
			(at -2.732271 10.270975 180)
			(unlocked yes)
			(layer "F.SilkS")
			(hide yes)
			(effects
				(font
					(size 0.762 0.762)
					(thickness 0.2032)
				)
			)
		)
		(sheetname "11-M2_RCB_MUX")
		(sheetfile "11-M2_RCB_MUX.kicad_sch")
		(duplicate_pad_numbers_are_jumpers no)
		(pad "1" smd rect
			(at -0.45 0)
			(size 0.55 0.55)
			(layers "F.Cu" "F.Mask" "F.Paste")
			(net "M2_GPS2_RX")
		)
		(pad "2" smd rect
			(at 0.45 0)
			(size 0.55 0.55)
			(layers "F.Cu" "F.Mask" "F.Paste")
			(net "GPS2_RX")
		)
	)
	(footprint "Vault:RESC1005X40X25NL05T05"
		(layer "F.Cu")
		(at 106.6216 56.7162 180)
		(property "Reference" "R163"
			(at 2.36762 0.329369 0)
			(unlocked yes)
			(layer "F.SilkS")
			(effects
				(font
					(size 0.762 0.762)
					(thickness 0.2032)
				)
			)
		)
		(property "Value" "DNI_27_1%_0402"
			(at -2.732271 10.270975 90)
			(unlocked yes)
			(layer "F.SilkS")
			(hide yes)
			(effects
				(font
					(size 0.762 0.762)
					(thickness 0.2032)
				)
			)
		)
		(sheetname "11-M2_RCB_MUX")
		(sheetfile "11-M2_RCB_MUX.kicad_sch")
		(duplicate_pad_numbers_are_jumpers no)
		(pad "1" smd rect
			(at -0.45 0 270)
			(size 0.55 0.55)
			(layers "F.Cu" "F.Mask" "F.Paste")
			(net "M2_GPS1_RX")
		)
		(pad "2" smd rect
			(at 0.45 0 270)
			(size 0.55 0.55)
			(layers "F.Cu" "F.Mask" "F.Paste")
			(net "GPS1_RX")
		)
	)
)
